(kicad_pcb
	(version 20260206)
	(generator "pcbnew")
	(generator_version "10.0")
	(general
		(thickness 1.6)
		(legacy_teardrops no)
	)
	(paper "A4")
	(title_block
		(title "03242023_DA0F0TMBIJ0_F0T_Motherboard_J_brd_V01_OCP.brd")
		(comment 1 "Grand Teton / footprints 3559-3563 of 6105")
	)
	(layers
		(0 "F.Cu" signal "TOP")
		(4 "In1.Cu" signal "GND")
		(6 "In2.Cu" signal "IN1")
		(8 "In3.Cu" signal "GND1")
		(10 "In4.Cu" signal "IN2")
		(12 "In5.Cu" signal "GND2")
		(14 "In6.Cu" signal "IN3")
		(16 "In7.Cu" signal "GND3")
		(18 "In8.Cu" signal "VCC")
		(20 "In9.Cu" signal "VCC1")
		(22 "In10.Cu" signal "GND4")
		(24 "In11.Cu" signal "IN4")
		(26 "In12.Cu" signal "GND5")
		(28 "In13.Cu" signal "IN5")
		(30 "In14.Cu" signal "GND6")
		(32 "In15.Cu" signal "IN6")
		(34 "In16.Cu" signal "GND7")
		(2 "B.Cu" signal "BOTTOM")
		(9 "F.Adhes" user "F.Adhesive")
		(11 "B.Adhes" user "B.Adhesive")
		(13 "F.Paste" user "Package Geometry/Pastemask Top")
		(15 "B.Paste" user "Package Geometry/Pastemask Bottom")
		(5 "F.SilkS" user "Ref Des/Silkscreen Top")
		(7 "B.SilkS" user "Ref Des/Silkscreen Bottom")
		(1 "F.Mask" user "Board Geometry/Soldermask Top")
		(3 "B.Mask" user "Board Geometry/Soldermask Bottom")
		(17 "Dwgs.User" user "User.Drawings")
		(19 "Cmts.User" user "User.Comments")
		(21 "Eco1.User" user "User.Eco1")
		(23 "Eco2.User" user "User.Eco2")
		(25 "Edge.Cuts" user "Board Geometry/Outline")
		(27 "Margin" user)
		(31 "F.CrtYd" user "Package Geometry/Place Bound Top")
		(29 "B.CrtYd" user "Package Geometry/Place Bound Bottom")
		(35 "F.Fab" user "Ref Des/Assembly Top")
		(33 "B.Fab" user "Ref Des/Assembly Bottom")
	)
	(footprint ""
		(layer "F.Cu")
		(at 477.30537 -148.043392 90)
		(property "Reference" "X44"
			(at -3.136392 -1.5367 90)
			(unlocked yes)
			(layer "F.SilkS")
			(effects
				(font
					(size 0.7874 0.5842)
					(thickness 0.1524)
				)
				(justify left)
			)
		)
		(property "Value" ""
			(at 0 0 90)
			(layer "F.Fab")
			(effects
				(font
					(size 1.27 1.27)
				)
			)
		)
		(property "Device Type" "TP_TDR_4P_FTS_TH-TP_TDR_4P_DIPA"
			(at 1.30175 1.27 180)
			(unlocked yes)
			(layer "F.Fab")
			(hide yes)
			(effects
				(font
					(size 0.635 0.4064)
					(thickness 0.1524)
				)
			)
		)
		(property "User Part Number" "N_A"
			(at 1.30175 1.27 180)
			(unlocked yes)
			(layer "Cmts.User")
			(hide yes)
			(effects
				(font
					(size 0.635 0.4064)
					(thickness 0.1524)
				)
			)
		)
		(duplicate_pad_numbers_are_jumpers no)
		(fp_line
			(start 2.54 -1.27)
			(end 0 -1.27)
			(stroke
				(width 0.1524)
				(type default)
			)
			(layer "F.SilkS")
		)
		(fp_line
			(start 0 -1.27)
			(end 0 -0.635)
			(stroke
				(width 0.1524)
				(type default)
			)
			(layer "F.SilkS")
		)
		(fp_line
			(start 2.54 -1.1303)
			(end 2.54 -1.27)
			(stroke
				(width 0.1524)
				(type default)
			)
			(layer "F.SilkS")
		)
		(fp_line
			(start 0 0.635)
			(end 0 1.905)
			(stroke
				(width 0.1524)
				(type default)
			)
			(layer "F.SilkS")
		)
		(fp_line
			(start 2.54 1.4097)
			(end 2.54 1.1303)
			(stroke
				(width 0.1524)
				(type default)
			)
			(layer "F.SilkS")
		)
		(fp_line
			(start 0 3.175)
			(end 0 3.81)
			(stroke
				(width 0.1524)
				(type default)
			)
			(layer "F.SilkS")
		)
		(fp_line
			(start 2.54 3.81)
			(end 2.54 3.6703)
			(stroke
				(width 0.1524)
				(type default)
			)
			(layer "F.SilkS")
		)
		(fp_line
			(start 0 3.81)
			(end 2.54 3.81)
			(stroke
				(width 0.1524)
				(type default)
			)
			(layer "F.SilkS")
		)
		(fp_poly
			(pts
				(xy -0.761746 0) (xy -2.285746 -0.762) (xy -2.285746 0.762)
			)
			(stroke
				(width 0)
				(type default)
			)
			(fill yes)
			(layer "F.SilkS")
		)
		(fp_line
			(start 2.54 -1.27)
			(end 0 -1.27)
			(stroke
				(width 0.1)
				(type default)
			)
			(layer "F.Fab")
		)
		(fp_line
			(start 0 -1.27)
			(end 0 3.81)
			(stroke
				(width 0.1)
				(type default)
			)
			(layer "F.Fab")
		)
		(fp_line
			(start 2.54 3.81)
			(end 2.54 -1.27)
			(stroke
				(width 0.1)
				(type default)
			)
			(layer "F.Fab")
		)
		(fp_line
			(start 0 3.81)
			(end 2.54 3.81)
			(stroke
				(width 0.1)
				(type default)
			)
			(layer "F.Fab")
		)
		(fp_poly
			(pts
				(xy -0.761746 0) (xy -2.285746 -0.762) (xy -2.285746 0.762)
			)
			(stroke
				(width 0)
				(type default)
			)
			(fill yes)
			(layer "F.Fab")
		)
		(pad "1" thru_hole circle
			(at 0 0 90)
			(size 1.0033 1.0033)
			(drill 0.249936)
			(layers "*.Cu" "*.Mask")
			(remove_unused_layers no)
			(net "TDR_DIFF_85_NECK_IN3_DN")
			(clearance 0.10795)
			(thermal_gap 0.10795)
			(padstack
				(mode front_inner_back)
				(layer "Inner"
					(shape circle)
					(size 0.8001 0.8001)
					(clearance 0.1524)
				)
				(layer "B.Cu"
					(shape circle)
					(size 1.0033 1.0033)
					(clearance 0.10795)
				)
			)
		)
		(pad "2" thru_hole circle
			(at 2.54 0 90)
			(size 1.9939 1.9939)
			(drill 0.249936)
			(layers "*.Cu" "*.Mask")
			(remove_unused_layers no)
			(net "T1_GND")
			(clearance 0.10795)
			(thermal_gap 0.10795)
			(padstack
				(mode front_inner_back)
				(layer "Inner"
					(shape circle)
					(size 0.8001 0.8001)
					(clearance 0.1524)
				)
				(layer "B.Cu"
					(shape circle)
					(size 1.9939 1.9939)
					(clearance 0.10795)
				)
			)
		)
		(pad "3" thru_hole circle
			(at 2.54 2.54 90)
			(size 1.9939 1.9939)
			(drill 0.249936)
			(layers "*.Cu" "*.Mask")
			(remove_unused_layers no)
			(net "T1_GND")
			(clearance 0.10795)
			(thermal_gap 0.10795)
			(padstack
				(mode front_inner_back)
				(layer "Inner"
					(shape circle)
					(size 0.8001 0.8001)
					(clearance 0.1524)
				)
				(layer "B.Cu"
					(shape circle)
					(size 1.9939 1.9939)
					(clearance 0.10795)
				)
			)
		)
		(pad "4" thru_hole circle
			(at 0 2.54 90)
			(size 1.0033 1.0033)
			(drill 0.249936)
			(layers "*.Cu" "*.Mask")
			(remove_unused_layers no)
			(net "TDR_DIFF_85_NECK_IN3_DP")
			(clearance 0.10795)
			(thermal_gap 0.10795)
			(padstack
				(mode front_inner_back)
				(layer "Inner"
					(shape circle)
					(size 0.8001 0.8001)
					(clearance 0.1524)
				)
				(layer "B.Cu"
					(shape circle)
					(size 1.0033 1.0033)
					(clearance 0.10795)
				)
			)
		)
	)
	(footprint ""
		(layer "F.Cu")
		(at 372.207282 -61.581792)
		(property "Reference" "C545"
			(at 0 0 0)
			(layer "F.SilkS")
			(hide yes)
			(effects
				(font
					(size 1.27 1.27)
				)
			)
		)
		(property "Value" ""
			(at 0 0 0)
			(layer "F.Fab")
			(effects
				(font
					(size 1.27 1.27)
				)
			)
		)
		(duplicate_pad_numbers_are_jumpers no)
		(fp_line
			(start -0.7874 -0.4064)
			(end 0.7874 -0.4064)
			(stroke
				(width 0.1524)
				(type default)
			)
			(layer "F.SilkS")
		)
		(fp_line
			(start -0.7874 0.4064)
			(end -0.7874 -0.4064)
			(stroke
				(width 0.1524)
				(type default)
			)
			(layer "F.SilkS")
		)
		(fp_line
			(start 0.7874 -0.4064)
			(end 0.7874 0.4064)
			(stroke
				(width 0.1524)
				(type default)
			)
			(layer "F.SilkS")
		)
		(fp_line
			(start 0.7874 0.4064)
			(end -0.7874 0.4064)
			(stroke
				(width 0.1524)
				(type default)
			)
			(layer "F.SilkS")
		)
		(fp_line
			(start -0.67945 -0.305054)
			(end -0.12065 -0.305054)
			(stroke
				(width 0.1)
				(type default)
			)
			(layer "F.Fab")
		)
		(fp_line
			(start -0.67945 0.3048)
			(end -0.67945 -0.305054)
			(stroke
				(width 0.1)
				(type default)
			)
			(layer "F.Fab")
		)
		(fp_line
			(start -0.12065 -0.305054)
			(end -0.12065 -0.2794)
			(stroke
				(width 0.1)
				(type default)
			)
			(layer "F.Fab")
		)
		(fp_line
			(start -0.12065 -0.2794)
			(end 0.12065 -0.2794)
			(stroke
				(width 0.1)
				(type default)
			)
			(layer "F.Fab")
		)
		(fp_line
			(start -0.12065 0.2794)
			(end -0.12065 0.3048)
			(stroke
				(width 0.1)
				(type default)
			)
			(layer "F.Fab")
		)
		(fp_line
			(start -0.12065 0.3048)
			(end -0.67945 0.3048)
			(stroke
				(width 0.1)
				(type default)
			)
			(layer "F.Fab")
		)
		(fp_line
			(start 0.120396 0.2794)
			(end -0.12065 0.2794)
			(stroke
				(width 0.1)
				(type default)
			)
			(layer "F.Fab")
		)
		(fp_line
			(start 0.120396 0.3048)
			(end 0.120396 0.2794)
			(stroke
				(width 0.1)
				(type default)
			)
			(layer "F.Fab")
		)
		(fp_line
			(start 0.12065 -0.3048)
			(end 0.67945 -0.3048)
			(stroke
				(width 0.1)
				(type default)
			)
			(layer "F.Fab")
		)
		(fp_line
			(start 0.12065 -0.2794)
			(end 0.12065 -0.3048)
			(stroke
				(width 0.1)
				(type default)
			)
			(layer "F.Fab")
		)
		(fp_line
			(start 0.67945 -0.3048)
			(end 0.67945 0.3048)
			(stroke
				(width 0.1)
				(type default)
			)
			(layer "F.Fab")
		)
		(fp_line
			(start 0.67945 0.3048)
			(end 0.120396 0.3048)
			(stroke
				(width 0.1)
				(type default)
			)
			(layer "F.Fab")
		)
		(pad "1" smd circle
			(at -0.40005 0)
			(size 0 0)
			(layers "F.Cu" "F.Mask" "F.Paste")
			(net "P3V3_AUX")
		)
		(pad "2" smd circle
			(at 0.40005 0)
			(size 0 0)
			(layers "F.Cu" "F.Mask" "F.Paste")
			(net "GND")
		)
	)
	(footprint ""
		(layer "F.Cu")
		(at 498.693948 -148.08454 90)
		(property "Reference" "X15"
			(at -3.42646 3.325622 90)
			(unlocked yes)
			(layer "F.SilkS")
			(effects
				(font
					(size 0.7874 0.5842)
					(thickness 0.1524)
				)
				(justify left)
			)
		)
		(property "Value" ""
			(at 0 0 90)
			(layer "F.Fab")
			(effects
				(font
					(size 1.27 1.27)
				)
			)
		)
		(property "Device Type" "TP_TDR_4P_FTS_MPKT4_H025P0200_I"
			(at 1.30175 1.27 180)
			(unlocked yes)
			(layer "F.Fab")
			(hide yes)
			(effects
				(font
					(size 0.635 0.4064)
					(thickness 0.1524)
				)
			)
		)
		(property "User Part Number" "TP15"
			(at 1.30175 1.27 180)
			(unlocked yes)
			(layer "Cmts.User")
			(hide yes)
			(effects
				(font
					(size 0.635 0.4064)
					(thickness 0.1524)
				)
			)
		)
		(duplicate_pad_numbers_are_jumpers no)
		(fp_line
			(start 2.54 -1.27)
			(end 0 -1.27)
			(stroke
				(width 0.1524)
				(type default)
			)
			(layer "F.SilkS")
		)
		(fp_line
			(start 0 -1.27)
			(end 0 -0.635)
			(stroke
				(width 0.1524)
				(type default)
			)
			(layer "F.SilkS")
		)
		(fp_line
			(start 2.54 -1.1303)
			(end 2.54 -1.27)
			(stroke
				(width 0.1524)
				(type default)
			)
			(layer "F.SilkS")
		)
		(fp_line
			(start 0 0.635)
			(end 0 1.905)
			(stroke
				(width 0.1524)
				(type default)
			)
			(layer "F.SilkS")
		)
		(fp_line
			(start 2.54 1.4097)
			(end 2.54 1.1303)
			(stroke
				(width 0.1524)
				(type default)
			)
			(layer "F.SilkS")
		)
		(fp_line
			(start 0 3.175)
			(end 0 3.81)
			(stroke
				(width 0.1524)
				(type default)
			)
			(layer "F.SilkS")
		)
		(fp_line
			(start 2.54 3.81)
			(end 2.54 3.6703)
			(stroke
				(width 0.1524)
				(type default)
			)
			(layer "F.SilkS")
		)
		(fp_line
			(start 0 3.81)
			(end 2.54 3.81)
			(stroke
				(width 0.1524)
				(type default)
			)
			(layer "F.SilkS")
		)
		(fp_poly
			(pts
				(xy -0.761746 0) (xy -2.285746 0.762) (xy -2.285746 -0.762)
			)
			(stroke
				(width 0)
				(type default)
			)
			(fill yes)
			(layer "F.SilkS")
		)
		(fp_line
			(start 2.54 -1.27)
			(end 0 -1.27)
			(stroke
				(width 0.1)
				(type default)
			)
			(layer "F.Fab")
		)
		(fp_line
			(start 0 -1.27)
			(end 0 3.81)
			(stroke
				(width 0.1)
				(type default)
			)
			(layer "F.Fab")
		)
		(fp_line
			(start 2.54 3.81)
			(end 2.54 -1.27)
			(stroke
				(width 0.1)
				(type default)
			)
			(layer "F.Fab")
		)
		(fp_line
			(start 0 3.81)
			(end 2.54 3.81)
			(stroke
				(width 0.1)
				(type default)
			)
			(layer "F.Fab")
		)
		(fp_poly
			(pts
				(xy -0.761746 0) (xy -2.285746 -0.762) (xy -2.285746 0.762)
			)
			(stroke
				(width 0)
				(type default)
			)
			(fill yes)
			(layer "F.Fab")
		)
		(pad "1" thru_hole circle
			(at 0 0 90)
			(size 1.0033 1.0033)
			(drill 0.249936)
			(layers "*.Cu" "*.Mask")
			(remove_unused_layers no)
			(net "TDR_DIFF_100_IN2_DP")
			(clearance 0.10795)
			(thermal_gap 0.10795)
			(padstack
				(mode front_inner_back)
				(layer "Inner"
					(shape circle)
					(size 0.8001 0.8001)
					(clearance 0.1524)
				)
				(layer "B.Cu"
					(shape circle)
					(size 1.0033 1.0033)
					(clearance 0.10795)
				)
			)
		)
		(pad "2" thru_hole circle
			(at 2.54 0 90)
			(size 1.9939 1.9939)
			(drill 0.249936)
			(layers "*.Cu" "*.Mask")
			(remove_unused_layers no)
			(net "T1_GND")
			(clearance 0.10795)
			(thermal_gap 0.10795)
			(padstack
				(mode front_inner_back)
				(layer "Inner"
					(shape circle)
					(size 0.8001 0.8001)
					(clearance 0.1524)
				)
				(layer "B.Cu"
					(shape circle)
					(size 1.9939 1.9939)
					(clearance 0.10795)
				)
			)
		)
		(pad "3" thru_hole circle
			(at 2.54 2.54 90)
			(size 1.9939 1.9939)
			(drill 0.249936)
			(layers "*.Cu" "*.Mask")
			(remove_unused_layers no)
			(net "T1_GND")
			(clearance 0.10795)
			(thermal_gap 0.10795)
			(padstack
				(mode front_inner_back)
				(layer "Inner"
					(shape circle)
					(size 0.8001 0.8001)
					(clearance 0.1524)
				)
				(layer "B.Cu"
					(shape circle)
					(size 1.9939 1.9939)
					(clearance 0.10795)
				)
			)
		)
		(pad "4" thru_hole circle
			(at 0 2.54 90)
			(size 1.0033 1.0033)
			(drill 0.249936)
			(layers "*.Cu" "*.Mask")
			(remove_unused_layers no)
			(net "TDR_DIFF_100_IN2_DN")
			(clearance 0.10795)
			(thermal_gap 0.10795)
			(padstack
				(mode front_inner_back)
				(layer "Inner"
					(shape circle)
					(size 0.8001 0.8001)
					(clearance 0.1524)
				)
				(layer "B.Cu"
					(shape circle)
					(size 1.0033 1.0033)
					(clearance 0.10795)
				)
			)
		)
	)
	(footprint ""
		(layer "F.Cu")
		(at 157.02788 -117.566948 180)
		(property "Reference" "R3174"
			(at 0 0 180)
			(layer "F.SilkS")
			(hide yes)
			(effects
				(font
					(size 1.27 1.27)
				)
			)
		)
		(property "Value" ""
			(at 0 0 180)
			(layer "F.Fab")
			(effects
				(font
					(size 1.27 1.27)
				)
			)
		)
		(duplicate_pad_numbers_are_jumpers no)
		(fp_line
			(start 0.7874 0.4064)
			(end -0.7874 0.4064)
			(stroke
				(width 0.1524)
				(type default)
			)
			(layer "F.SilkS")
		)
		(fp_line
			(start 0.7874 -0.4064)
			(end 0.7874 0.4064)
			(stroke
				(width 0.1524)
				(type default)
			)
			(layer "F.SilkS")
		)
		(fp_line
			(start -0.7874 0.4064)
			(end -0.7874 -0.4064)
			(stroke
				(width 0.1524)
				(type default)
			)
			(layer "F.SilkS")
		)
		(fp_line
			(start -0.7874 -0.4064)
			(end 0.7874 -0.4064)
			(stroke
				(width 0.1524)
				(type default)
			)
			(layer "F.SilkS")
		)
		(fp_line
			(start 0.67945 0.3048)
			(end 0.120396 0.3048)
			(stroke
				(width 0.1)
				(type default)
			)
			(layer "F.Fab")
		)
		(fp_line
			(start 0.67945 -0.3048)
			(end 0.67945 0.3048)
			(stroke
				(width 0.1)
				(type default)
			)
			(layer "F.Fab")
		)
		(fp_line
			(start 0.12065 -0.2794)
			(end 0.12065 -0.3048)
			(stroke
				(width 0.1)
				(type default)
			)
			(layer "F.Fab")
		)
		(fp_line
			(start 0.12065 -0.3048)
			(end 0.67945 -0.3048)
			(stroke
				(width 0.1)
				(type default)
			)
			(layer "F.Fab")
		)
		(fp_line
			(start 0.120396 0.3048)
			(end 0.120396 0.2794)
			(stroke
				(width 0.1)
				(type default)
			)
			(layer "F.Fab")
		)
		(fp_line
			(start 0.120396 0.2794)
			(end -0.12065 0.2794)
			(stroke
				(width 0.1)
				(type default)
			)
			(layer "F.Fab")
		)
		(fp_line
			(start -0.12065 0.3048)
			(end -0.67945 0.3048)
			(stroke
				(width 0.1)
				(type default)
			)
			(layer "F.Fab")
		)
		(fp_line
			(start -0.12065 0.2794)
			(end -0.12065 0.3048)
			(stroke
				(width 0.1)
				(type default)
			)
			(layer "F.Fab")
		)
		(fp_line
			(start -0.12065 -0.2794)
			(end 0.12065 -0.2794)
			(stroke
				(width 0.1)
				(type default)
			)
			(layer "F.Fab")
		)
		(fp_line
			(start -0.12065 -0.305054)
			(end -0.12065 -0.2794)
			(stroke
				(width 0.1)
				(type default)
			)
			(layer "F.Fab")
		)
		(fp_line
			(start -0.67945 0.3048)
			(end -0.67945 -0.305054)
			(stroke
				(width 0.1)
				(type default)
			)
			(layer "F.Fab")
		)
		(fp_line
			(start -0.67945 -0.305054)
			(end -0.12065 -0.305054)
			(stroke
				(width 0.1)
				(type default)
			)
			(layer "F.Fab")
		)
		(pad "1" smd circle
			(at -0.40005 0 180)
			(size 0 0)
			(layers "F.Cu" "F.Mask" "F.Paste")
			(net "SGPIO_OCP_V3_2_DATAIN")
		)
		(pad "2" smd circle
			(at 0.40005 0 180)
			(size 0 0)
			(layers "F.Cu" "F.Mask" "F.Paste")
			(net "P3V3_OCP_V3_2")
		)
	)
	(footprint ""
		(layer "F.Cu")
		(at 107.28833 -240.277142 90)
		(property "Reference" "C296"
			(at 0 0 90)
			(layer "F.SilkS")
			(hide yes)
			(effects
				(font
					(size 1.27 1.27)
				)
			)
		)
		(property "Value" ""
			(at 0 0 90)
			(layer "F.Fab")
			(effects
				(font
					(size 1.27 1.27)
				)
			)
		)
		(duplicate_pad_numbers_are_jumpers no)
		(fp_line
			(start 0.7874 -0.4064)
			(end 0.7874 0.4064)
			(stroke
				(width 0.1524)
				(type default)
			)
			(layer "F.SilkS")
		)
		(fp_line
			(start -0.7874 -0.4064)
			(end 0.7874 -0.4064)
			(stroke
				(width 0.1524)
				(type default)
			)
			(layer "F.SilkS")
		)
		(fp_line
			(start 0.7874 0.4064)
			(end -0.7874 0.4064)
			(stroke
				(width 0.1524)
				(type default)
			)
			(layer "F.SilkS")
		)
		(fp_line
			(start -0.7874 0.4064)
			(end -0.7874 -0.4064)
			(stroke
				(width 0.1524)
				(type default)
			)
			(layer "F.SilkS")
		)
		(fp_line
			(start -0.12065 -0.305054)
			(end -0.12065 -0.2794)
			(stroke
				(width 0.1)
				(type default)
			)
			(layer "F.Fab")
		)
		(fp_line
			(start -0.67945 -0.305054)
			(end -0.12065 -0.305054)
			(stroke
				(width 0.1)
				(type default)
			)
			(layer "F.Fab")
		)
		(fp_line
			(start 0.67945 -0.3048)
			(end 0.67945 0.3048)
			(stroke
				(width 0.1)
				(type default)
			)
			(layer "F.Fab")
		)
		(fp_line
			(start 0.12065 -0.3048)
			(end 0.67945 -0.3048)
			(stroke
				(width 0.1)
				(type default)
			)
			(layer "F.Fab")
		)
		(fp_line
			(start 0.12065 -0.2794)
			(end 0.12065 -0.3048)
			(stroke
				(width 0.1)
				(type default)
			)
			(layer "F.Fab")
		)
		(fp_line
			(start -0.12065 -0.2794)
			(end 0.12065 -0.2794)
			(stroke
				(width 0.1)
				(type default)
			)
			(layer "F.Fab")
		)
		(fp_line
			(start 0.120396 0.2794)
			(end -0.12065 0.2794)
			(stroke
				(width 0.1)
				(type default)
			)
			(layer "F.Fab")
		)
		(fp_line
			(start -0.12065 0.2794)
			(end -0.12065 0.3048)
			(stroke
				(width 0.1)
				(type default)
			)
			(layer "F.Fab")
		)
		(fp_line
			(start 0.67945 0.3048)
			(end 0.120396 0.3048)
			(stroke
				(width 0.1)
				(type default)
			)
			(layer "F.Fab")
		)
		(fp_line
			(start 0.120396 0.3048)
			(end 0.120396 0.2794)
			(stroke
				(width 0.1)
				(type default)
			)
			(layer "F.Fab")
		)
		(fp_line
			(start -0.12065 0.3048)
			(end -0.67945 0.3048)
			(stroke
				(width 0.1)
				(type default)
			)
			(layer "F.Fab")
		)
		(fp_line
			(start -0.67945 0.3048)
			(end -0.67945 -0.305054)
			(stroke
				(width 0.1)
				(type default)
			)
			(layer "F.Fab")
		)
		(pad "1" smd circle
			(at -0.40005 0 90)
			(size 0 0)
			(layers "F.Cu" "F.Mask" "F.Paste")
			(net "PVCCIN_CPU1")
		)
		(pad "2" smd circle
			(at 0.40005 0 90)
			(size 0 0)
			(layers "F.Cu" "F.Mask" "F.Paste")
			(net "GND")
		)
	)
)
